# HDMI-MIPI Bridge — assets/stackup.csv
Name;Type;Material;Thickness[mm];Constant
F.Mask;Top Solder Mask;;0.01;
F.Cu;copper;;0.035;
dielectric 1;core;FR4;0.254;4.2
In1.Cu;copper;;0.035;
dielectric 2;prepreg;FR4;0.24;4.2
In2.Cu;copper;;0.035;
dielectric 3;core;FR4;0.254;4.2
B.Cu;copper;;0.035;
B.Mask;Bottom Solder Mask;;0.01;
